(kicad_pcb
	(version 20260206)
	(generator "pcbnew")
	(generator_version "10.0")
	(general
		(thickness 1.6)
		(legacy_teardrops no)
	)
	(paper "A4")
	(title_block
		(title "9052_F0T_PDB_Converter_Brick_F_V03_1208_1600_OCP.brd")
		(comment 1 "Grand Teton / footprints 415-420 of 578")
	)
	(layers
		(0 "F.Cu" signal "TOP")
		(4 "In1.Cu" signal "GND")
		(6 "In2.Cu" signal "IN1")
		(8 "In3.Cu" signal "GND1")
		(10 "In4.Cu" signal "VCC")
		(12 "In5.Cu" signal "VCC1")
		(14 "In6.Cu" signal "GND2")
		(16 "In7.Cu" signal "IN2")
		(18 "In8.Cu" signal "GND3")
		(2 "B.Cu" signal "BOTTOM")
		(9 "F.Adhes" user "F.Adhesive")
		(11 "B.Adhes" user "B.Adhesive")
		(13 "F.Paste" user "Package Geometry/Pastemask Top")
		(15 "B.Paste" user "Package Geometry/Pastemask Bottom")
		(5 "F.SilkS" user "Ref Des/Silkscreen Top")
		(7 "B.SilkS" user "Ref Des/Silkscreen Bottom")
		(1 "F.Mask" user "Board Geometry/Soldermask Top")
		(3 "B.Mask" user "Board Geometry/Soldermask Bottom")
		(17 "Dwgs.User" user "User.Drawings")
		(19 "Cmts.User" user "User.Comments")
		(21 "Eco1.User" user "User.Eco1")
		(23 "Eco2.User" user "User.Eco2")
		(25 "Edge.Cuts" user "Board Geometry/Outline")
		(27 "Margin" user)
		(31 "F.CrtYd" user "Package Geometry/Place Bound Top")
		(29 "B.CrtYd" user "Package Geometry/Place Bound Bottom")
		(35 "F.Fab" user "Ref Des/Assembly Top")
		(33 "B.Fab" user "Ref Des/Assembly Bottom")
	)
	(footprint ""
		(layer "B.Cu")
		(at 217.424 -67.183 90)
		(property "Reference" "R138"
			(at 0 0 90)
			(layer "B.SilkS")
			(hide yes)
			(effects
				(font
					(size 1.27 1.27)
				)
				(justify mirror)
			)
		)
		(property "Value" ""
			(at 0 0 90)
			(layer "B.Fab")
			(effects
				(font
					(size 1.27 1.27)
				)
				(justify mirror)
			)
		)
		(duplicate_pad_numbers_are_jumpers no)
		(fp_line
			(start 0.7874 -0.4064)
			(end -0.7874 -0.4064)
			(stroke
				(width 0.1524)
				(type default)
			)
			(layer "B.SilkS")
		)
		(fp_line
			(start -0.7874 -0.4064)
			(end -0.7874 0.4064)
			(stroke
				(width 0.1524)
				(type default)
			)
			(layer "B.SilkS")
		)
		(fp_line
			(start 0.7874 0.4064)
			(end 0.7874 -0.4064)
			(stroke
				(width 0.1524)
				(type default)
			)
			(layer "B.SilkS")
		)
		(fp_line
			(start -0.7874 0.4064)
			(end 0.7874 0.4064)
			(stroke
				(width 0.1524)
				(type default)
			)
			(layer "B.SilkS")
		)
		(fp_line
			(start 0.67945 -0.305054)
			(end 0.12065 -0.305054)
			(stroke
				(width 0.1)
				(type default)
			)
			(layer "B.Fab")
		)
		(fp_line
			(start 0.12065 -0.305054)
			(end 0.12065 -0.2794)
			(stroke
				(width 0.1)
				(type default)
			)
			(layer "B.Fab")
		)
		(fp_line
			(start -0.12065 -0.3048)
			(end -0.67945 -0.3048)
			(stroke
				(width 0.1)
				(type default)
			)
			(layer "B.Fab")
		)
		(fp_line
			(start -0.67945 -0.3048)
			(end -0.67945 0.3048)
			(stroke
				(width 0.1)
				(type default)
			)
			(layer "B.Fab")
		)
		(fp_line
			(start 0.12065 -0.2794)
			(end -0.12065 -0.2794)
			(stroke
				(width 0.1)
				(type default)
			)
			(layer "B.Fab")
		)
		(fp_line
			(start -0.12065 -0.2794)
			(end -0.12065 -0.3048)
			(stroke
				(width 0.1)
				(type default)
			)
			(layer "B.Fab")
		)
		(fp_line
			(start 0.12065 0.2794)
			(end 0.12065 0.3048)
			(stroke
				(width 0.1)
				(type default)
			)
			(layer "B.Fab")
		)
		(fp_line
			(start -0.120396 0.2794)
			(end 0.12065 0.2794)
			(stroke
				(width 0.1)
				(type default)
			)
			(layer "B.Fab")
		)
		(fp_line
			(start 0.67945 0.3048)
			(end 0.67945 -0.305054)
			(stroke
				(width 0.1)
				(type default)
			)
			(layer "B.Fab")
		)
		(fp_line
			(start 0.12065 0.3048)
			(end 0.67945 0.3048)
			(stroke
				(width 0.1)
				(type default)
			)
			(layer "B.Fab")
		)
		(fp_line
			(start -0.120396 0.3048)
			(end -0.120396 0.2794)
			(stroke
				(width 0.1)
				(type default)
			)
			(layer "B.Fab")
		)
		(fp_line
			(start -0.67945 0.3048)
			(end -0.120396 0.3048)
			(stroke
				(width 0.1)
				(type default)
			)
			(layer "B.Fab")
		)
		(pad "1" smd circle
			(at 0.40005 0 270)
			(size 0 0)
			(layers "B.Cu" "B.Mask" "B.Paste")
			(net "BOARD_ID_0")
		)
		(pad "2" smd circle
			(at -0.40005 0 270)
			(size 0 0)
			(layers "B.Cu" "B.Mask" "B.Paste")
			(net "GND")
		)
	)
	(footprint ""
		(layer "B.Cu")
		(at 224.536 -70.993 -90)
		(property "Reference" "C18"
			(at 0 0 90)
			(layer "B.SilkS")
			(hide yes)
			(effects
				(font
					(size 1.27 1.27)
				)
				(justify mirror)
			)
		)
		(property "Value" ""
			(at 0 0 90)
			(layer "B.Fab")
			(effects
				(font
					(size 1.27 1.27)
				)
				(justify mirror)
			)
		)
		(duplicate_pad_numbers_are_jumpers no)
		(fp_line
			(start -0.7874 0.4064)
			(end 0.7874 0.4064)
			(stroke
				(width 0.1524)
				(type default)
			)
			(layer "B.SilkS")
		)
		(fp_line
			(start 0.7874 0.4064)
			(end 0.7874 -0.4064)
			(stroke
				(width 0.1524)
				(type default)
			)
			(layer "B.SilkS")
		)
		(fp_line
			(start -0.7874 -0.4064)
			(end -0.7874 0.4064)
			(stroke
				(width 0.1524)
				(type default)
			)
			(layer "B.SilkS")
		)
		(fp_line
			(start 0.7874 -0.4064)
			(end -0.7874 -0.4064)
			(stroke
				(width 0.1524)
				(type default)
			)
			(layer "B.SilkS")
		)
		(fp_line
			(start -0.67945 0.3048)
			(end -0.120396 0.3048)
			(stroke
				(width 0.1)
				(type default)
			)
			(layer "B.Fab")
		)
		(fp_line
			(start -0.120396 0.3048)
			(end -0.120396 0.2794)
			(stroke
				(width 0.1)
				(type default)
			)
			(layer "B.Fab")
		)
		(fp_line
			(start 0.12065 0.3048)
			(end 0.67945 0.3048)
			(stroke
				(width 0.1)
				(type default)
			)
			(layer "B.Fab")
		)
		(fp_line
			(start 0.67945 0.3048)
			(end 0.67945 -0.305054)
			(stroke
				(width 0.1)
				(type default)
			)
			(layer "B.Fab")
		)
		(fp_line
			(start -0.120396 0.2794)
			(end 0.12065 0.2794)
			(stroke
				(width 0.1)
				(type default)
			)
			(layer "B.Fab")
		)
		(fp_line
			(start 0.12065 0.2794)
			(end 0.12065 0.3048)
			(stroke
				(width 0.1)
				(type default)
			)
			(layer "B.Fab")
		)
		(fp_line
			(start -0.12065 -0.2794)
			(end -0.12065 -0.3048)
			(stroke
				(width 0.1)
				(type default)
			)
			(layer "B.Fab")
		)
		(fp_line
			(start 0.12065 -0.2794)
			(end -0.12065 -0.2794)
			(stroke
				(width 0.1)
				(type default)
			)
			(layer "B.Fab")
		)
		(fp_line
			(start -0.67945 -0.3048)
			(end -0.67945 0.3048)
			(stroke
				(width 0.1)
				(type default)
			)
			(layer "B.Fab")
		)
		(fp_line
			(start -0.12065 -0.3048)
			(end -0.67945 -0.3048)
			(stroke
				(width 0.1)
				(type default)
			)
			(layer "B.Fab")
		)
		(fp_line
			(start 0.12065 -0.305054)
			(end 0.12065 -0.2794)
			(stroke
				(width 0.1)
				(type default)
			)
			(layer "B.Fab")
		)
		(fp_line
			(start 0.67945 -0.305054)
			(end 0.12065 -0.305054)
			(stroke
				(width 0.1)
				(type default)
			)
			(layer "B.Fab")
		)
		(pad "1" smd circle
			(at 0.40005 0 90)
			(size 0 0)
			(layers "B.Cu" "B.Mask" "B.Paste")
			(net "GPU_HSC_R_EN")
		)
		(pad "2" smd circle
			(at -0.40005 0 90)
			(size 0 0)
			(layers "B.Cu" "B.Mask" "B.Paste")
			(net "GND")
		)
	)
	(footprint ""
		(layer "B.Cu")
		(at 267.716 -25.527 180)
		(property "Reference" "D12"
			(at 1.1811 -2.32537 0)
			(unlocked yes)
			(layer "B.SilkS")
			(effects
				(font
					(size 0.7874 0.5842)
					(thickness 0.1524)
				)
				(justify left mirror)
			)
		)
		(property "Value" ""
			(at 0 0 0)
			(layer "B.Fab")
			(effects
				(font
					(size 1.27 1.27)
				)
				(justify mirror)
			)
		)
		(duplicate_pad_numbers_are_jumpers no)
		(fp_line
			(start 3.400044 1.459992)
			(end 3.400044 -1.459992)
			(stroke
				(width 0.1524)
				(type default)
			)
			(layer "B.SilkS")
		)
		(fp_line
			(start 3.400044 -1.459992)
			(end -4.107942 -1.459992)
			(stroke
				(width 0.1524)
				(type default)
			)
			(layer "B.SilkS")
		)
		(fp_line
			(start -4.107942 1.459992)
			(end 3.400044 1.459992)
			(stroke
				(width 0.1524)
				(type default)
			)
			(layer "B.SilkS")
		)
		(fp_line
			(start -4.107942 -1.459992)
			(end -4.107942 1.459992)
			(stroke
				(width 0.1524)
				(type default)
			)
			(layer "B.SilkS")
		)
		(fp_poly
			(pts
				(xy -4.107942 -1.459992) (xy -4.107942 1.459992) (xy -3.308096 1.459992) (xy -3.308096 -1.459992)
			)
			(stroke
				(width 0)
				(type default)
			)
			(fill yes)
			(layer "B.SilkS")
		)
		(fp_line
			(start 2.29997 1.459992)
			(end 2.29997 -1.459992)
			(stroke
				(width 0.1)
				(type default)
			)
			(layer "B.Fab")
		)
		(fp_line
			(start 2.29997 -1.459992)
			(end -2.29997 -1.459992)
			(stroke
				(width 0.1)
				(type default)
			)
			(layer "B.Fab")
		)
		(fp_line
			(start -2.29997 1.459992)
			(end 2.29997 1.459992)
			(stroke
				(width 0.1)
				(type default)
			)
			(layer "B.Fab")
		)
		(fp_line
			(start -2.29997 -1.459992)
			(end -2.29997 1.459992)
			(stroke
				(width 0.1)
				(type default)
			)
			(layer "B.Fab")
		)
		(fp_text user "+"
			(at 4.7752 -0.12065 180)
			(unlocked yes)
			(layer "B.SilkS")
			(effects
				(font
					(size 1.905 1.4224)
					(thickness 0.1524)
				)
				(justify left mirror)
			)
		)
		(fp_text user "-"
			(at -5.4102 0.29845 0)
			(unlocked yes)
			(layer "B.SilkS")
			(effects
				(font
					(size 1.905 1.4224)
					(thickness 0.1524)
				)
				(justify left mirror)
			)
		)
		(fp_text user "+"
			(at 4.7752 -0.12065 180)
			(unlocked yes)
			(layer "B.Fab")
			(effects
				(font
					(size 1.905 1.4224)
					(thickness 0.1524)
				)
				(justify left mirror)
			)
		)
		(fp_text user "-"
			(at -5.4102 0.29845 0)
			(unlocked yes)
			(layer "B.Fab")
			(effects
				(font
					(size 1.905 1.4224)
					(thickness 0.1524)
				)
				(justify left mirror)
			)
		)
		(pad "A" smd rect
			(at 1.999996 0 270)
			(size 1.7018 2.5146)
			(layers "B.Cu" "B.Mask" "B.Paste")
			(net "P52V_HS1_EN_DELAY")
		)
		(pad "C" smd rect
			(at -1.999996 0 270)
			(size 1.7018 2.5146)
			(layers "B.Cu" "B.Mask" "B.Paste")
			(net "P52V_HS1_EN")
		)
	)
	(footprint ""
		(layer "B.Cu")
		(at 94.361 -77.47 180)
		(property "Reference" "C58"
			(at 0 0 0)
			(layer "B.SilkS")
			(hide yes)
			(effects
				(font
					(size 1.27 1.27)
				)
				(justify mirror)
			)
		)
		(property "Value" ""
			(at 0 0 0)
			(layer "B.Fab")
			(effects
				(font
					(size 1.27 1.27)
				)
				(justify mirror)
			)
		)
		(duplicate_pad_numbers_are_jumpers no)
		(fp_line
			(start 0.7874 0.4064)
			(end 0.7874 -0.4064)
			(stroke
				(width 0.1524)
				(type default)
			)
			(layer "B.SilkS")
		)
		(fp_line
			(start 0.7874 -0.4064)
			(end -0.7874 -0.4064)
			(stroke
				(width 0.1524)
				(type default)
			)
			(layer "B.SilkS")
		)
		(fp_line
			(start -0.7874 0.4064)
			(end 0.7874 0.4064)
			(stroke
				(width 0.1524)
				(type default)
			)
			(layer "B.SilkS")
		)
		(fp_line
			(start -0.7874 -0.4064)
			(end -0.7874 0.4064)
			(stroke
				(width 0.1524)
				(type default)
			)
			(layer "B.SilkS")
		)
		(fp_line
			(start 0.67945 0.3048)
			(end 0.67945 -0.305054)
			(stroke
				(width 0.1)
				(type default)
			)
			(layer "B.Fab")
		)
		(fp_line
			(start 0.67945 -0.305054)
			(end 0.12065 -0.305054)
			(stroke
				(width 0.1)
				(type default)
			)
			(layer "B.Fab")
		)
		(fp_line
			(start 0.12065 0.3048)
			(end 0.67945 0.3048)
			(stroke
				(width 0.1)
				(type default)
			)
			(layer "B.Fab")
		)
		(fp_line
			(start 0.12065 0.2794)
			(end 0.12065 0.3048)
			(stroke
				(width 0.1)
				(type default)
			)
			(layer "B.Fab")
		)
		(fp_line
			(start 0.12065 -0.2794)
			(end -0.12065 -0.2794)
			(stroke
				(width 0.1)
				(type default)
			)
			(layer "B.Fab")
		)
		(fp_line
			(start 0.12065 -0.305054)
			(end 0.12065 -0.2794)
			(stroke
				(width 0.1)
				(type default)
			)
			(layer "B.Fab")
		)
		(fp_line
			(start -0.120396 0.3048)
			(end -0.120396 0.2794)
			(stroke
				(width 0.1)
				(type default)
			)
			(layer "B.Fab")
		)
		(fp_line
			(start -0.120396 0.2794)
			(end 0.12065 0.2794)
			(stroke
				(width 0.1)
				(type default)
			)
			(layer "B.Fab")
		)
		(fp_line
			(start -0.12065 -0.2794)
			(end -0.12065 -0.3048)
			(stroke
				(width 0.1)
				(type default)
			)
			(layer "B.Fab")
		)
		(fp_line
			(start -0.12065 -0.3048)
			(end -0.67945 -0.3048)
			(stroke
				(width 0.1)
				(type default)
			)
			(layer "B.Fab")
		)
		(fp_line
			(start -0.67945 0.3048)
			(end -0.120396 0.3048)
			(stroke
				(width 0.1)
				(type default)
			)
			(layer "B.Fab")
		)
		(fp_line
			(start -0.67945 -0.3048)
			(end -0.67945 0.3048)
			(stroke
				(width 0.1)
				(type default)
			)
			(layer "B.Fab")
		)
		(pad "1" smd circle
			(at 0.40005 0)
			(size 0 0)
			(layers "B.Cu" "B.Mask" "B.Paste")
			(net "P12V_BRICK1_ALERT_N")
		)
		(pad "2" smd circle
			(at -0.40005 0)
			(size 0 0)
			(layers "B.Cu" "B.Mask" "B.Paste")
			(net "GND")
		)
	)
	(footprint ""
		(layer "B.Cu")
		(at 209.804 -67.183 90)
		(property "Reference" "R21"
			(at 0 0 90)
			(layer "B.SilkS")
			(hide yes)
			(effects
				(font
					(size 1.27 1.27)
				)
				(justify mirror)
			)
		)
		(property "Value" ""
			(at 0 0 90)
			(layer "B.Fab")
			(effects
				(font
					(size 1.27 1.27)
				)
				(justify mirror)
			)
		)
		(duplicate_pad_numbers_are_jumpers no)
		(fp_line
			(start 0.7874 -0.4064)
			(end -0.7874 -0.4064)
			(stroke
				(width 0.1524)
				(type default)
			)
			(layer "B.SilkS")
		)
		(fp_line
			(start -0.7874 -0.4064)
			(end -0.7874 0.4064)
			(stroke
				(width 0.1524)
				(type default)
			)
			(layer "B.SilkS")
		)
		(fp_line
			(start 0.7874 0.4064)
			(end 0.7874 -0.4064)
			(stroke
				(width 0.1524)
				(type default)
			)
			(layer "B.SilkS")
		)
		(fp_line
			(start -0.7874 0.4064)
			(end 0.7874 0.4064)
			(stroke
				(width 0.1524)
				(type default)
			)
			(layer "B.SilkS")
		)
		(fp_line
			(start 0.67945 -0.305054)
			(end 0.12065 -0.305054)
			(stroke
				(width 0.1)
				(type default)
			)
			(layer "B.Fab")
		)
		(fp_line
			(start 0.12065 -0.305054)
			(end 0.12065 -0.2794)
			(stroke
				(width 0.1)
				(type default)
			)
			(layer "B.Fab")
		)
		(fp_line
			(start -0.12065 -0.3048)
			(end -0.67945 -0.3048)
			(stroke
				(width 0.1)
				(type default)
			)
			(layer "B.Fab")
		)
		(fp_line
			(start -0.67945 -0.3048)
			(end -0.67945 0.3048)
			(stroke
				(width 0.1)
				(type default)
			)
			(layer "B.Fab")
		)
		(fp_line
			(start 0.12065 -0.2794)
			(end -0.12065 -0.2794)
			(stroke
				(width 0.1)
				(type default)
			)
			(layer "B.Fab")
		)
		(fp_line
			(start -0.12065 -0.2794)
			(end -0.12065 -0.3048)
			(stroke
				(width 0.1)
				(type default)
			)
			(layer "B.Fab")
		)
		(fp_line
			(start 0.12065 0.2794)
			(end 0.12065 0.3048)
			(stroke
				(width 0.1)
				(type default)
			)
			(layer "B.Fab")
		)
		(fp_line
			(start -0.120396 0.2794)
			(end 0.12065 0.2794)
			(stroke
				(width 0.1)
				(type default)
			)
			(layer "B.Fab")
		)
		(fp_line
			(start 0.67945 0.3048)
			(end 0.67945 -0.305054)
			(stroke
				(width 0.1)
				(type default)
			)
			(layer "B.Fab")
		)
		(fp_line
			(start 0.12065 0.3048)
			(end 0.67945 0.3048)
			(stroke
				(width 0.1)
				(type default)
			)
			(layer "B.Fab")
		)
		(fp_line
			(start -0.120396 0.3048)
			(end -0.120396 0.2794)
			(stroke
				(width 0.1)
				(type default)
			)
			(layer "B.Fab")
		)
		(fp_line
			(start -0.67945 0.3048)
			(end -0.120396 0.3048)
			(stroke
				(width 0.1)
				(type default)
			)
			(layer "B.Fab")
		)
		(pad "1" smd circle
			(at 0.40005 0 270)
			(size 0 0)
			(layers "B.Cu" "B.Mask" "B.Paste")
			(net "PCA9555_A0")
		)
		(pad "2" smd circle
			(at -0.40005 0 270)
			(size 0 0)
			(layers "B.Cu" "B.Mask" "B.Paste")
			(net "GND")
		)
	)
	(footprint ""
		(layer "B.Cu")
		(at 143.002 -114.173 -90)
		(property "Reference" "R398"
			(at 0 0 90)
			(layer "B.SilkS")
			(hide yes)
			(effects
				(font
					(size 1.27 1.27)
				)
				(justify mirror)
			)
		)
		(property "Value" ""
			(at 0 0 90)
			(layer "B.Fab")
			(effects
				(font
					(size 1.27 1.27)
				)
				(justify mirror)
			)
		)
		(duplicate_pad_numbers_are_jumpers no)
		(fp_line
			(start -1.651 0.8382)
			(end 1.651 0.8382)
			(stroke
				(width 0.1524)
				(type default)
			)
			(layer "B.SilkS")
		)
		(fp_line
			(start 1.651 0.8382)
			(end 1.651 -0.8382)
			(stroke
				(width 0.1524)
				(type default)
			)
			(layer "B.SilkS")
		)
		(fp_line
			(start -1.651 -0.8382)
			(end -1.651 0.8382)
			(stroke
				(width 0.1524)
				(type default)
			)
			(layer "B.SilkS")
		)
		(fp_line
			(start 1.651 -0.8382)
			(end -1.651 -0.8382)
			(stroke
				(width 0.1524)
				(type default)
			)
			(layer "B.SilkS")
		)
		(fp_line
			(start -1.560576 0.7366)
			(end -1.560576 -0.7366)
			(stroke
				(width 0.1)
				(type default)
			)
			(layer "B.Fab")
		)
		(fp_line
			(start -1.524 0.7366)
			(end -1.560576 0.7366)
			(stroke
				(width 0.1)
				(type default)
			)
			(layer "B.Fab")
		)
		(fp_line
			(start 1.524 0.7366)
			(end -1.524 0.7366)
			(stroke
				(width 0.1)
				(type default)
			)
			(layer "B.Fab")
		)
		(fp_line
			(start 1.559814 0.7366)
			(end 1.524 0.7366)
			(stroke
				(width 0.1)
				(type default)
			)
			(layer "B.Fab")
		)
		(fp_line
			(start -1.560576 -0.7366)
			(end -1.524 -0.7366)
			(stroke
				(width 0.1)
				(type default)
			)
			(layer "B.Fab")
		)
		(fp_line
			(start -1.524 -0.7366)
			(end 1.524 -0.7366)
			(stroke
				(width 0.1)
				(type default)
			)
			(layer "B.Fab")
		)
		(fp_line
			(start 1.524 -0.7366)
			(end 1.559814 -0.7366)
			(stroke
				(width 0.1)
				(type default)
			)
			(layer "B.Fab")
		)
		(fp_line
			(start 1.559814 -0.7366)
			(end 1.559814 0.7366)
			(stroke
				(width 0.1)
				(type default)
			)
			(layer "B.Fab")
		)
		(pad "1" smd rect
			(at 0.94996 0 270)
			(size 1.1176 1.3716)
			(layers "B.Cu" "B.Mask" "B.Paste")
			(net "P52V_HS")
		)
		(pad "2" smd rect
			(at -0.94996 0 270)
			(size 1.1176 1.3716)
			(layers "B.Cu" "B.Mask" "B.Paste")
			(net "BRICK_P12V0_EN_N")
		)
	)
)
